#ISCELL
  cls sheet_a1 *
  *
#CELL
  passive resistor *
  page5_i100
#CELL
  passive resistor *
  page5_i101
#CELL
  passive resistor *
  page5_i102
#CELL
  passive resistor *
  page5_i103
#ISCELL
  cls offpage_bi *
  page5_i104
#ISCELL
  cls offpage_in *
  page5_i105
#ISCELL
  cls offpage_bi *
  page5_i106
#ISCELL
  cls offpage_in *
  page5_i107
#CELL
  passive resistor *
  page5_i111
#CELL
  passive resistor *
  page5_i112
#ISCELL
  cls offpage_out *
  page5_i113
#ISCELL
  cls offpage_bi *
  page5_i114
#CELL
  passive resistor *
  page5_i115
#CELL
  passive resistor *
  page5_i116
#ISCELL
  cls offpage_out *
  page5_i117
#ISCELL
  cls offpage_bi *
  page5_i118
#ISCELL
  cls offpage_in *
  page5_i124
#CELL
  passive resistor *
  page5_i125
#CELL
  connector conn_hdr_2x2_m_s_smt *
  page5_i126
#CELL
  connector conn_hdr_2x2_m_s_smt *
  page5_i127
#ISCELL
  cls gnd_sg *
  page5_i128
#ISCELL
  cls offpage_in *
  page5_i129
#CELL
  passive resistor *
  page5_i130
#ISCELL
  cls gnd_sg *
  page5_i139
#ISCELL
  cls gnd_sg *
  page5_i147
#CELL
  memory 24lc16bt_i_st_tssop8 *
  page5_i148
#CELL
  memory 24lc16bt_i_st_tssop8 *
  page5_i151
#CELL
  passive resistor *
  page5_i153
#CELL
  passive resistor *
  page5_i156
#ISCELL
  cls vcc *
  page5_i159
#CELL
  passive resistor *
  page5_i160
#CELL
  passive resistor *
  page5_i161
#CELL
  passive resistor *
  page5_i162
#CELL
  passive resistor *
  page5_i165
#CELL
  passive resistor *
  page5_i166
#CELL
  passive resistor *
  page5_i167
#ISCELL
  cls vcc *
  page5_i168
#CELL
  passive resistor *
  page5_i169
#ISCELL
  cls gnd_sg *
  page5_i170
#CELL
  passive capacitor *
  page5_i171
#ISCELL
  cls vcc *
  page5_i172
#CELL
  passive resistor *
  page5_i173
#ISCELL
  cls offpage_in *
  page5_i174
#ISCELL
  cls offpage_bi *
  page5_i175
#ISCELL
  cls offpage_out *
  page5_i176
#ISCELL
  cls offpage_bi *
  page5_i177
#ISCELL
  cls offpage_in *
  page5_i178
#ISCELL
  cls offpage_in *
  page5_i179
#ISCELL
  cls offpage_in *
  page5_i180
#ISCELL
  cls offpage_in *
  page5_i181
#ISCELL
  cls offpage_out *
  page5_i25
#ISCELL
  cls offpage_bi *
  page5_i26
#ISCELL
  cls offpage_out *
  page5_i27
#ISCELL
  cls offpage_bi *
  page5_i28
#ISCELL
  cls offpage_out *
  page5_i29
#ISCELL
  cls offpage_bi *
  page5_i30
#ISCELL
  cls offpage_out *
  page5_i31
#ISCELL
  cls offpage_bi *
  page5_i32
#CELL
  interface pca9546apw_tssop16 *
  page5_i33
#CELL
  passive resistor *
  page5_i4
#CELL
  passive capacitor *
  page5_i45
#ISCELL
  cls offpage_bi *
  page5_i5
#CELL
  passive resistor *
  page5_i52
#ISCELL
  cls gnd_sg *
  page5_i53
#CELL
  interface pca9546apw_tssop16 *
  page5_i54
#CELL
  passive resistor *
  page5_i55
#ISCELL
  cls offpage_in *
  page5_i6
#CELL
  passive resistor *
  page5_i60
#CELL
  passive resistor *
  page5_i66
#CELL
  passive resistor *
  page5_i67
#CELL
  passive resistor *
  page5_i68
#CELL
  passive resistor *
  page5_i69
#CELL
  passive resistor *
  page5_i72
#ISCELL
  cls offpage_in *
  page5_i73
#ISCELL
  cls offpage_bi *
  page5_i74
#ISCELL
  cls vcc *
  page5_i76
#ISCELL
  cls vcc *
  page5_i77
#ISCELL
  cls vcc *
  page5_i78
#CELL
  passive resistor *
  page5_i80
#CELL
  passive resistor *
  page5_i81
#CELL
  passive resistor *
  page5_i82
#CELL
  passive resistor *
  page5_i83
#CELL
  passive resistor *
  page5_i84
#CELL
  passive resistor *
  page5_i85
#CELL
  passive resistor *
  page5_i86
#CELL
  passive resistor *
  page5_i87
#CELL
  passive resistor *
  page5_i88
#CELL
  memory at24mac402_sot23_5 *
  page5_i89
#ISCELL
  cls gnd_sg *
  page5_i9
#CELL
  passive resistor *
  page5_i90
#ISCELL
  cls vcc *
  page5_i91
#CELL
  passive capacitor *
  page5_i92
#ISCELL
  cls gnd_sg *
  page5_i93
#CELL
  passive resistor *
  page5_i94
#CELL
  passive resistor *
  page5_i95
#CELL
  passive resistor *
  page5_i96
#CELL
  passive resistor *
  page5_i97
#ISCELL
  cls gnd_sg *
  page5_i98
#ISCELL
  cls vcc *
  page5_i99
